# S9S_MB_2U (Grand Teton) — schematic netlist excerpt (pin names and nets, part order shuffled) for the footprints in the layout excerpt that follows; sources: Cadence DE-HDL packaged netlist, KiCad conversion of 03242023_DA0F0TMBIJ0_F0T_Motherboard_J_brd_V01_OCP.brd

R2834  Q_RES  4.7K 5% CHIP  pkg 0402LF  page 148 : A = P3V3_AUX ; B = RST_BMC_FROM_SWB

Q50  MOSFET_NCH_DUAL  PJT138K IC  pkg SOT363XD  page 213
  S1  = GND
  G1  = PWRGD_P5V_AUX
  D2  = PWRGD_P5V_AUX_R2
  S2  = GND
  G2  = PWRGD_P5V_AUX_R1
  D1  = PWRGD_P5V_AUX_R1

(kicad_pcb
	(version 20260206)
	(generator "pcbnew")
	(generator_version "10.0")
	(general
		(thickness 1.6)
		(legacy_teardrops no)
	)
	(paper "A4")
	(title_block
		(title "03242023_DA0F0TMBIJ0_F0T_Motherboard_J_brd_V01_OCP.brd")
		(comment 1 "Grand Teton / footprints 1085-1086 of 6105")
	)
	(layers
		(0 "F.Cu" signal "TOP")
		(4 "In1.Cu" signal "GND")
		(6 "In2.Cu" signal "IN1")
		(8 "In3.Cu" signal "GND1")
		(10 "In4.Cu" signal "IN2")
		(12 "In5.Cu" signal "GND2")
		(14 "In6.Cu" signal "IN3")
		(16 "In7.Cu" signal "GND3")
		(18 "In8.Cu" signal "VCC")
		(20 "In9.Cu" signal "VCC1")
		(22 "In10.Cu" signal "GND4")
		(24 "In11.Cu" signal "IN4")
		(26 "In12.Cu" signal "GND5")
		(28 "In13.Cu" signal "IN5")
		(30 "In14.Cu" signal "GND6")
		(32 "In15.Cu" signal "IN6")
		(34 "In16.Cu" signal "GND7")
		(2 "B.Cu" signal "BOTTOM")
		(9 "F.Adhes" user "F.Adhesive")
		(11 "B.Adhes" user "B.Adhesive")
		(13 "F.Paste" user "Package Geometry/Pastemask Top")
		(15 "B.Paste" user "Package Geometry/Pastemask Bottom")
		(5 "F.SilkS" user "Ref Des/Silkscreen Top")
		(7 "B.SilkS" user "Ref Des/Silkscreen Bottom")
		(1 "F.Mask" user "Board Geometry/Soldermask Top")
		(3 "B.Mask" user "Board Geometry/Soldermask Bottom")
		(17 "Dwgs.User" user "User.Drawings")
		(19 "Cmts.User" user "User.Comments")
		(21 "Eco1.User" user "User.Eco1")
		(23 "Eco2.User" user "User.Eco2")
		(25 "Edge.Cuts" user "Board Geometry/Outline")
		(27 "Margin" user)
		(31 "F.CrtYd" user "Package Geometry/Place Bound Top")
		(29 "B.CrtYd" user "Package Geometry/Place Bound Bottom")
		(35 "F.Fab" user "Ref Des/Assembly Top")
		(33 "B.Fab" user "Ref Des/Assembly Bottom")
	)
	(footprint ""
		(layer "F.Cu")
		(at 153.13914 -119.001032 90)
		(property "Reference" "Q50"
			(at 0.792226 -2.610104 0)
			(unlocked yes)
			(layer "F.SilkS")
			(effects
				(font
					(size 0.7874 0.5842)
					(thickness 0.1524)
				)
			)
		)
		(property "Value" ""
			(at 0 0 90)
			(layer "F.Fab")
			(effects
				(font
					(size 1.27 1.27)
				)
			)
		)
		(duplicate_pad_numbers_are_jumpers no)
		(fp_line
			(start 1.332738 -1.100074)
			(end 1.332738 1.100074)
			(stroke
				(width 0.1524)
				(type default)
			)
			(layer "F.SilkS")
		)
		(fp_line
			(start 0.4826 -1.100074)
			(end 1.332738 -1.100074)
			(stroke
				(width 0.1524)
				(type default)
			)
			(layer "F.SilkS")
		)
		(fp_line
			(start -0.4826 -1.100074)
			(end 0 -0.541274)
			(stroke
				(width 0.1524)
				(type default)
			)
			(layer "F.SilkS")
		)
		(fp_line
			(start -1.332738 -1.100074)
			(end -0.4826 -1.100074)
			(stroke
				(width 0.1524)
				(type default)
			)
			(layer "F.SilkS")
		)
		(fp_line
			(start 0 -0.541274)
			(end 0.4826 -1.100074)
			(stroke
				(width 0.1524)
				(type default)
			)
			(layer "F.SilkS")
		)
		(fp_line
			(start 1.332738 1.100074)
			(end -1.332738 1.100074)
			(stroke
				(width 0.1524)
				(type default)
			)
			(layer "F.SilkS")
		)
		(fp_line
			(start -1.332738 1.100074)
			(end -1.332738 -1.100074)
			(stroke
				(width 0.1524)
				(type default)
			)
			(layer "F.SilkS")
		)
		(fp_poly
			(pts
				(xy -1.442466 -2.226056) (xy -0.74041 -2.226056) (xy -1.091438 -1.524)
			)
			(stroke
				(width 0)
				(type default)
			)
			(fill yes)
			(layer "F.SilkS")
		)
		(fp_line
			(start 0.674878 -1.100074)
			(end 0.674878 1.100074)
			(stroke
				(width 0.1)
				(type default)
			)
			(layer "F.Fab")
		)
		(fp_line
			(start -0.674878 -1.100074)
			(end 0.674878 -1.100074)
			(stroke
				(width 0.1)
				(type default)
			)
			(layer "F.Fab")
		)
		(fp_line
			(start 0.674878 1.100074)
			(end -0.674878 1.100074)
			(stroke
				(width 0.1)
				(type default)
			)
			(layer "F.Fab")
		)
		(fp_line
			(start -0.674878 1.100074)
			(end -0.674878 -1.100074)
			(stroke
				(width 0.1)
				(type default)
			)
			(layer "F.Fab")
		)
		(fp_poly
			(pts
				(xy -2.2352 -0.298958) (xy -2.2352 -1.001014) (xy -1.533144 -0.649986)
			)
			(stroke
				(width 0)
				(type default)
			)
			(fill yes)
			(layer "F.Fab")
		)
		(pad "1" smd rect
			(at -0.94996 -0.649986 180)
			(size 0.4318 0.508)
			(layers "F.Cu" "F.Mask" "F.Paste")
			(net "GND")
		)
		(pad "2" smd rect
			(at -0.94996 0 180)
			(size 0.4318 0.508)
			(layers "F.Cu" "F.Mask" "F.Paste")
			(net "PWRGD_P5V_AUX")
		)
		(pad "3" smd rect
			(at -0.94996 0.649986 180)
			(size 0.4318 0.508)
			(layers "F.Cu" "F.Mask" "F.Paste")
			(net "PWRGD_P5V_AUX_R2")
		)
		(pad "4" smd rect
			(at 0.94996 0.649986 180)
			(size 0.4318 0.508)
			(layers "F.Cu" "F.Mask" "F.Paste")
			(net "GND")
		)
		(pad "5" smd rect
			(at 0.94996 0 180)
			(size 0.4318 0.508)
			(layers "F.Cu" "F.Mask" "F.Paste")
			(net "PWRGD_P5V_AUX_R1")
		)
		(pad "6" smd rect
			(at 0.94996 -0.649986 180)
			(size 0.4318 0.508)
			(layers "F.Cu" "F.Mask" "F.Paste")
			(net "PWRGD_P5V_AUX_R1")
		)
	)
	(footprint ""
		(layer "F.Cu")
		(at 431.989992 -381.218948 180)
		(property "Reference" "R2834"
			(at 0 0 180)
			(layer "F.SilkS")
			(hide yes)
			(effects
				(font
					(size 1.27 1.27)
				)
			)
		)
		(property "Value" ""
			(at 0 0 180)
			(layer "F.Fab")
			(effects
				(font
					(size 1.27 1.27)
				)
			)
		)
		(duplicate_pad_numbers_are_jumpers no)
		(fp_line
			(start 0.7874 0.4064)
			(end -0.7874 0.4064)
			(stroke
				(width 0.1524)
				(type default)
			)
			(layer "F.SilkS")
		)
		(fp_line
			(start 0.7874 -0.4064)
			(end 0.7874 0.4064)
			(stroke
				(width 0.1524)
				(type default)
			)
			(layer "F.SilkS")
		)
		(fp_line
			(start -0.7874 0.4064)
			(end -0.7874 -0.4064)
			(stroke
				(width 0.1524)
				(type default)
			)
			(layer "F.SilkS")
		)
		(fp_line
			(start -0.7874 -0.4064)
			(end 0.7874 -0.4064)
			(stroke
				(width 0.1524)
				(type default)
			)
			(layer "F.SilkS")
		)
		(fp_line
			(start 0.67945 0.3048)
			(end 0.120396 0.3048)
			(stroke
				(width 0.1)
				(type default)
			)
			(layer "F.Fab")
		)
		(fp_line
			(start 0.67945 -0.3048)
			(end 0.67945 0.3048)
			(stroke
				(width 0.1)
				(type default)
			)
			(layer "F.Fab")
		)
		(fp_line
			(start 0.12065 -0.2794)
			(end 0.12065 -0.3048)
			(stroke
				(width 0.1)
				(type default)
			)
			(layer "F.Fab")
		)
		(fp_line
			(start 0.12065 -0.3048)
			(end 0.67945 -0.3048)
			(stroke
				(width 0.1)
				(type default)
			)
			(layer "F.Fab")
		)
		(fp_line
			(start 0.120396 0.3048)
			(end 0.120396 0.2794)
			(stroke
				(width 0.1)
				(type default)
			)
			(layer "F.Fab")
		)
		(fp_line
			(start 0.120396 0.2794)
			(end -0.12065 0.2794)
			(stroke
				(width 0.1)
				(type default)
			)
			(layer "F.Fab")
		)
		(fp_line
			(start -0.12065 0.3048)
			(end -0.67945 0.3048)
			(stroke
				(width 0.1)
				(type default)
			)
			(layer "F.Fab")
		)
		(fp_line
			(start -0.12065 0.2794)
			(end -0.12065 0.3048)
			(stroke
				(width 0.1)
				(type default)
			)
			(layer "F.Fab")
		)
		(fp_line
			(start -0.12065 -0.2794)
			(end 0.12065 -0.2794)
			(stroke
				(width 0.1)
				(type default)
			)
			(layer "F.Fab")
		)
		(fp_line
			(start -0.12065 -0.305054)
			(end -0.12065 -0.2794)
			(stroke
				(width 0.1)
				(type default)
			)
			(layer "F.Fab")
		)
		(fp_line
			(start -0.67945 0.3048)
			(end -0.67945 -0.305054)
			(stroke
				(width 0.1)
				(type default)
			)
			(layer "F.Fab")
		)
		(fp_line
			(start -0.67945 -0.305054)
			(end -0.12065 -0.305054)
			(stroke
				(width 0.1)
				(type default)
			)
			(layer "F.Fab")
		)
		(pad "1" smd circle
			(at -0.40005 0 180)
			(size 0 0)
			(layers "F.Cu" "F.Mask" "F.Paste")
			(net "P3V3_AUX")
		)
		(pad "2" smd circle
			(at 0.40005 0 180)
			(size 0 0)
			(layers "F.Cu" "F.Mask" "F.Paste")
			(net "RST_BMC_FROM_SWB")
		)
	)
)
